FILE_TYPE = MACRO_DRAWING;
SET COLOR_WIRE YELLOW;
SET COLOR_PROP MONO;
SET COLOR_DOT WHITE;
SET COLOR_ARC YELLOW;
SET COLOR_BODY GREEN;
SET COLOR_NOTE MONO;
SET PROP_DISPLAY VALUE;
SET PAGE_NUMBER P178;
FORCEADD RES..1
(-800 3725);
FORCEPROP 1 LAST LOCATION R8D20
J 0
(-825 3775);
DISPLAY 0.617021 (-825 3775);
PAINT AQUA (-825 3775);
FORCEPROP 1 LAST PART_NUMBER G21796-047
J 0
(-525 3675);
DISPLAY 0.617021 (-525 3675);
PAINT BLUE (-525 3675);
FORCEPROP 1 LAST VALUE 49.9
J 2
(-825 3675);
DISPLAY 0.617021 (-825 3675);
PAINT SKYBLUE (-825 3675);
FORCEPROP 1 LAST TOLERANCE 1%
J 0
(-800 3675);
DISPLAY 0.617021 (-800 3675);
PAINT SKYBLUE (-800 3675);
FORCEPROP 1 LAST PACK_TYPE 0402
J 0
(-625 3675);
DISPLAY 0.617021 (-625 3675);
PAINT SKYBLUE (-625 3675);
FORCEPROP 1 LAST MATERIAL CHIP
J 0
(-725 3675);
DISPLAY 0.617021 (-725 3675);
PAINT SKYBLUE (-725 3675);
FORCEPROP 1 LAST WATTAGE 1/16W
J 2
(-925 3675);
DISPLAY 0.617021 (-925 3675);
PAINT SKYBLUE (-925 3675);
FORCEPROP 1 LASTPIN (-700 3725) $PN 2
J 0
(-738 3737);
DISPLAY 0.617021 (-738 3737);
PAINT ORANGE (-738 3737);
FORCEPROP 1 LASTPIN (-900 3725) $PN 1
J 0
(-888 3737);
DISPLAY 0.617021 (-888 3737);
PAINT ORANGE (-888 3737);
FORCEPROP 2 LAST CDS_LIB mstr_discrete
J 0
(-800 3725);
PAINT MONO (-800 3725);
DISPLAY INVISIBLE (-800 3725);
FORCEPROP 2 LAST SEC_TYPE 0402
J 0
(-850 3925);
DISPLAY 1.021277 (-850 3925);
PAINT ORANGE (-850 3925);
DISPLAY INVISIBLE (-850 3925);
FORCEPROP 0 LAST BOM_COST ST_SATA
J 0
(-800 3925);
DISPLAY 1.021277 (-800 3925);
PAINT ORANGE (-800 3925);
DISPLAY INVISIBLE (-800 3925);
FORCEPROP 2 LAST SEC 1
J 0
(-850 3925);
DISPLAY 0.680851 (-850 3925);
PAINT MONO (-850 3925);
DISPLAY INVISIBLE (-850 3925);
FORCEPROP 2 LAST CDS_LOCATION R8D20
J 0
(-825 3775);
DISPLAY 0.617021 (-825 3775);
PAINT AQUA (-825 3775);
DISPLAY INVISIBLE (-825 3775);
FORCEPROP 1 LAST PATH I1
J 0
(-850 3875);
DISPLAY 0.978723 (-850 3875);
PAINT WHITE (-850 3875);
DISPLAY INVISIBLE (-850 3875);
FORCEPROP 0 LAST ROOM ST_SATA
J 0
(-850 3925);
DISPLAY 1.021277 (-850 3925);
PAINT ORANGE (-850 3925);
DISPLAY INVISIBLE (-850 3925);
FORCEADD OFFPAGE..2
(1450 3425);
FORCEPROP 2 LAST $XR0 173 
J 0
(1639 3425);
DISPLAY 0.638298 (1639 3425);
PAINT MONO (1639 3425);
FORCEPROP 2 LAST CDS_LIB mstr_standard
J 0
(1450 3425);
PAINT MONO (1450 3425);
DISPLAY INVISIBLE (1450 3425);
FORCEPROP 1 LAST OFFPAGE TRUE
J 0
(1775 3300);
DISPLAY 0.872340 (1775 3300);
PAINT GREEN (1775 3300);
DISPLAY INVISIBLE (1775 3300);
FORCEPROP 1 LAST COMMENT_BODY TRUE
J 0
(1405 3330);
DISPLAY 0.872340 (1405 3330);
PAINT GREEN (1405 3330);
DISPLAY INVISIBLE (1405 3330);
FORCEPROP 2 LAST PATH I10
J 0
(1625 3500);
DISPLAY 1.021277 (1625 3500);
PAINT ORANGE (1625 3500);
DISPLAY INVISIBLE (1625 3500);
FORCEADD RES..1
(-800 3425);
FORCEPROP 1 LAST LOCATION R2N31
J 0
(-825 3475);
DISPLAY 0.617021 (-825 3475);
PAINT AQUA (-825 3475);
FORCEPROP 1 LAST PART_NUMBER G21796-047
J 0
(-525 3375);
DISPLAY 0.617021 (-525 3375);
PAINT BLUE (-525 3375);
FORCEPROP 1 LAST VALUE 49.9
J 2
(-825 3375);
DISPLAY 0.617021 (-825 3375);
PAINT SKYBLUE (-825 3375);
FORCEPROP 1 LAST TOLERANCE 1%
J 0
(-800 3375);
DISPLAY 0.617021 (-800 3375);
PAINT SKYBLUE (-800 3375);
FORCEPROP 1 LAST PACK_TYPE 0402
J 0
(-625 3375);
DISPLAY 0.617021 (-625 3375);
PAINT SKYBLUE (-625 3375);
FORCEPROP 1 LAST MATERIAL CHIP
J 0
(-725 3375);
DISPLAY 0.617021 (-725 3375);
PAINT SKYBLUE (-725 3375);
FORCEPROP 1 LAST WATTAGE 1/16W
J 2
(-925 3375);
DISPLAY 0.617021 (-925 3375);
PAINT SKYBLUE (-925 3375);
FORCEPROP 1 LASTPIN (-700 3425) $PN 2
J 0
(-738 3437);
DISPLAY 0.617021 (-738 3437);
PAINT ORANGE (-738 3437);
FORCEPROP 1 LASTPIN (-900 3425) $PN 1
J 0
(-888 3437);
DISPLAY 0.617021 (-888 3437);
PAINT ORANGE (-888 3437);
FORCEPROP 2 LAST CDS_LIB mstr_discrete
J 0
(-800 3425);
PAINT MONO (-800 3425);
DISPLAY INVISIBLE (-800 3425);
FORCEPROP 2 LAST SEC_TYPE 0402
J 0
(-850 3625);
DISPLAY 1.021277 (-850 3625);
PAINT ORANGE (-850 3625);
DISPLAY INVISIBLE (-850 3625);
FORCEPROP 0 LAST BOM_COST ST_SATA
J 0
(-800 3625);
DISPLAY 1.021277 (-800 3625);
PAINT ORANGE (-800 3625);
DISPLAY INVISIBLE (-800 3625);
FORCEPROP 2 LAST SEC 1
J 0
(-850 3625);
DISPLAY 0.680851 (-850 3625);
PAINT MONO (-850 3625);
DISPLAY INVISIBLE (-850 3625);
FORCEPROP 1 LAST PATH I11
J 0
(-850 3575);
DISPLAY 0.978723 (-850 3575);
PAINT WHITE (-850 3575);
DISPLAY INVISIBLE (-850 3575);
FORCEPROP 0 LAST ROOM ST_SATA
J 0
(-850 3625);
DISPLAY 1.021277 (-850 3625);
PAINT ORANGE (-850 3625);
DISPLAY INVISIBLE (-850 3625);
FORCEADD RES..2
R 2
(225 4125);
FORCEPROP 1 LAST LOCATION R2L15
J 2
(180 4250);
DISPLAY 0.617021 (180 4250);
PAINT AQUA (180 4250);
FORCEPROP 1 LAST PART_NUMBER G21796-001
J 2
(185 4000);
DISPLAY 0.617021 (185 4000);
PAINT BLUE (185 4000);
FORCEPROP 1 LAST VALUE 2.0K
J 2
(180 4200);
DISPLAY 0.617021 (180 4200);
PAINT SKYBLUE (180 4200);
FORCEPROP 1 LAST TOLERANCE 1%
J 2
(180 4150);
DISPLAY 0.617021 (180 4150);
PAINT SKYBLUE (180 4150);
FORCEPROP 1 LAST PACK_TYPE 0402
J 2
(185 3950);
DISPLAY 0.617021 (185 3950);
PAINT SKYBLUE (185 3950);
FORCEPROP 1 LAST MATERIAL CHIP
J 2
(185 4050);
DISPLAY 0.617021 (185 4050);
PAINT SKYBLUE (185 4050);
FORCEPROP 1 LAST WATTAGE 1/16W
J 2
(185 4100);
DISPLAY 0.617021 (185 4100);
PAINT SKYBLUE (185 4100);
FORCEPROP 1 LASTPIN (225 4025) $PN 2
J 2
(220 4035);
DISPLAY 0.617021 (220 4035);
PAINT ORANGE (220 4035);
FORCEPROP 1 LASTPIN (225 4225) $PN 1
J 2
(220 4187);
DISPLAY 0.617021 (220 4187);
PAINT ORANGE (220 4187);
FORCEPROP 2 LAST CDS_LIB mstr_discrete
J 0
(225 4125);
PAINT MONO (225 4125);
DISPLAY INVISIBLE (225 4125);
FORCEPROP 2 LAST SEC_TYPE 0402
J 0
(175 4350);
DISPLAY 1.021277 (175 4350);
PAINT ORANGE (175 4350);
DISPLAY INVISIBLE (175 4350);
FORCEPROP 0 LAST BOM_COST ST_SATA
J 0
(200 4350);
DISPLAY 1.021277 (200 4350);
PAINT ORANGE (200 4350);
DISPLAY INVISIBLE (200 4350);
FORCEPROP 2 LAST SEC 1
J 0
(175 4350);
DISPLAY 0.680851 (175 4350);
PAINT MONO (175 4350);
DISPLAY INVISIBLE (175 4350);
FORCEPROP 2 LAST CDS_LOCATION R2L15
J 2
(180 4250);
DISPLAY 0.617021 (180 4250);
PAINT AQUA (180 4250);
DISPLAY INVISIBLE (180 4250);
FORCEPROP 1 LAST PATH I12
J 2
(175 4300);
DISPLAY 0.978723 (175 4300);
PAINT WHITE (175 4300);
DISPLAY INVISIBLE (175 4300);
FORCEPROP 0 LAST ROOM ST_SATA
J 0
(200 4350);
DISPLAY 1.021277 (200 4350);
PAINT ORANGE (200 4350);
DISPLAY INVISIBLE (200 4350);
FORCEADD RES..2
R 2
(575 4125);
FORCEPROP 1 LAST LOCATION R2L11
J 2
(530 4250);
DISPLAY 0.617021 (530 4250);
PAINT AQUA (530 4250);
FORCEPROP 1 LAST VALUE 2.0K
J 2
(530 4200);
DISPLAY 0.617021 (530 4200);
PAINT SKYBLUE (530 4200);
FORCEPROP 1 LAST TOLERANCE 1%
J 2
(530 4150);
DISPLAY 0.617021 (530 4150);
PAINT SKYBLUE (530 4150);
FORCEPROP 1 LAST MATERIAL CHIP
J 2
(535 4050);
DISPLAY 0.617021 (535 4050);
PAINT SKYBLUE (535 4050);
FORCEPROP 1 LAST WATTAGE 1/16W
J 2
(535 4100);
DISPLAY 0.617021 (535 4100);
PAINT SKYBLUE (535 4100);
FORCEPROP 1 LASTPIN (575 4025) $PN 2
J 2
(570 4035);
DISPLAY 0.617021 (570 4035);
PAINT ORANGE (570 4035);
FORCEPROP 1 LASTPIN (575 4225) $PN 1
J 2
(570 4187);
DISPLAY 0.617021 (570 4187);
PAINT ORANGE (570 4187);
FORCEPROP 1 LAST PART_NUMBER G21796-001
J 2
(535 4000);
DISPLAY 0.617021 (535 4000);
PAINT BLUE (535 4000);
FORCEPROP 1 LAST PACK_TYPE 0402
J 2
(535 3950);
DISPLAY 0.617021 (535 3950);
PAINT SKYBLUE (535 3950);
FORCEPROP 2 LAST CDS_LIB mstr_discrete
J 0
(575 4125);
PAINT MONO (575 4125);
DISPLAY INVISIBLE (575 4125);
FORCEPROP 2 LAST SEC_TYPE 0402
J 0
(525 4350);
DISPLAY 1.021277 (525 4350);
PAINT ORANGE (525 4350);
DISPLAY INVISIBLE (525 4350);
FORCEPROP 0 LAST BOM_COST ST_SATA
J 0
(550 4350);
DISPLAY 1.021277 (550 4350);
PAINT ORANGE (550 4350);
DISPLAY INVISIBLE (550 4350);
FORCEPROP 2 LAST SEC 1
J 0
(525 4350);
DISPLAY 0.680851 (525 4350);
PAINT MONO (525 4350);
DISPLAY INVISIBLE (525 4350);
FORCEPROP 2 LAST CDS_LOCATION R2L11
J 2
(530 4250);
DISPLAY 0.617021 (530 4250);
PAINT AQUA (530 4250);
DISPLAY INVISIBLE (530 4250);
FORCEPROP 1 LAST PATH I13
J 2
(525 4300);
DISPLAY 0.978723 (525 4300);
PAINT WHITE (525 4300);
DISPLAY INVISIBLE (525 4300);
FORCEPROP 0 LAST ROOM ST_SATA
J 0
(550 4350);
DISPLAY 1.021277 (550 4350);
PAINT ORANGE (550 4350);
DISPLAY INVISIBLE (550 4350);
FORCEADD RES..2
R 2
(475 2225);
FORCEPROP 1 LAST LOCATION R2L6
J 2
(430 2350);
DISPLAY 0.617021 (430 2350);
PAINT AQUA (430 2350);
FORCEPROP 1 LAST PART_NUMBER G21796-001
J 2
(435 2100);
DISPLAY 0.617021 (435 2100);
PAINT BLUE (435 2100);
FORCEPROP 1 LAST VALUE 2.0K
J 2
(430 2300);
DISPLAY 0.617021 (430 2300);
PAINT SKYBLUE (430 2300);
FORCEPROP 1 LAST TOLERANCE 1%
J 2
(430 2250);
DISPLAY 0.617021 (430 2250);
PAINT SKYBLUE (430 2250);
FORCEPROP 1 LAST PACK_TYPE 0402
J 2
(435 2050);
DISPLAY 0.617021 (435 2050);
PAINT SKYBLUE (435 2050);
FORCEPROP 1 LAST MATERIAL CHIP
J 2
(435 2150);
DISPLAY 0.617021 (435 2150);
PAINT SKYBLUE (435 2150);
FORCEPROP 1 LAST WATTAGE 1/16W
J 2
(435 2200);
DISPLAY 0.617021 (435 2200);
PAINT SKYBLUE (435 2200);
FORCEPROP 1 LASTPIN (475 2125) $PN 2
J 2
(470 2135);
DISPLAY 0.617021 (470 2135);
PAINT ORANGE (470 2135);
FORCEPROP 1 LASTPIN (475 2325) $PN 1
J 2
(470 2287);
DISPLAY 0.617021 (470 2287);
PAINT ORANGE (470 2287);
FORCEPROP 0 LAST BOM_COST ST_SATA
J 0
(450 2450);
DISPLAY 1.021277 (450 2450);
PAINT ORANGE (450 2450);
DISPLAY INVISIBLE (450 2450);
FORCEPROP 2 LAST SEC_TYPE 0402
J 0
(425 2450);
DISPLAY 1.021277 (425 2450);
PAINT ORANGE (425 2450);
DISPLAY INVISIBLE (425 2450);
FORCEPROP 2 LAST CDS_LIB mstr_discrete
J 0
(475 2225);
PAINT MONO (475 2225);
DISPLAY INVISIBLE (475 2225);
FORCEPROP 2 LAST SEC 1
J 0
(425 2450);
DISPLAY 0.680851 (425 2450);
PAINT MONO (425 2450);
DISPLAY INVISIBLE (425 2450);
FORCEPROP 2 LAST CDS_LOCATION R2L6
J 2
(430 2350);
DISPLAY 0.617021 (430 2350);
PAINT AQUA (430 2350);
DISPLAY INVISIBLE (430 2350);
FORCEPROP 1 LAST PATH I17
J 2
(425 2400);
DISPLAY 0.978723 (425 2400);
PAINT WHITE (425 2400);
DISPLAY INVISIBLE (425 2400);
FORCEPROP 0 LAST ROOM ST_SATA
J 0
(450 2450);
DISPLAY 1.021277 (450 2450);
PAINT ORANGE (450 2450);
DISPLAY INVISIBLE (450 2450);
FORCEADD RES..2
R 2
(125 2225);
FORCEPROP 1 LAST LOCATION R2L4
J 2
(80 2350);
DISPLAY 0.617021 (80 2350);
PAINT AQUA (80 2350);
FORCEPROP 1 LAST PART_NUMBER G21796-001
J 2
(85 2100);
DISPLAY 0.617021 (85 2100);
PAINT BLUE (85 2100);
FORCEPROP 1 LAST VALUE 2.0K
J 2
(80 2300);
DISPLAY 0.617021 (80 2300);
PAINT SKYBLUE (80 2300);
FORCEPROP 1 LAST TOLERANCE 1%
J 2
(80 2250);
DISPLAY 0.617021 (80 2250);
PAINT SKYBLUE (80 2250);
FORCEPROP 1 LAST PACK_TYPE 0402
J 2
(85 2050);
DISPLAY 0.617021 (85 2050);
PAINT SKYBLUE (85 2050);
FORCEPROP 1 LAST MATERIAL CHIP
J 2
(85 2150);
DISPLAY 0.617021 (85 2150);
PAINT SKYBLUE (85 2150);
FORCEPROP 1 LAST WATTAGE 1/16W
J 2
(85 2200);
DISPLAY 0.617021 (85 2200);
PAINT SKYBLUE (85 2200);
FORCEPROP 1 LASTPIN (125 2125) $PN 2
J 2
(120 2135);
DISPLAY 0.617021 (120 2135);
PAINT ORANGE (120 2135);
FORCEPROP 1 LASTPIN (125 2325) $PN 1
J 2
(120 2287);
DISPLAY 0.617021 (120 2287);
PAINT ORANGE (120 2287);
FORCEPROP 0 LAST BOM_COST ST_SATA
J 0
(100 2450);
DISPLAY 1.021277 (100 2450);
PAINT ORANGE (100 2450);
DISPLAY INVISIBLE (100 2450);
FORCEPROP 2 LAST SEC_TYPE 0402
J 0
(75 2450);
DISPLAY 1.021277 (75 2450);
PAINT ORANGE (75 2450);
DISPLAY INVISIBLE (75 2450);
FORCEPROP 2 LAST CDS_LIB mstr_discrete
J 0
(125 2225);
PAINT MONO (125 2225);
DISPLAY INVISIBLE (125 2225);
FORCEPROP 2 LAST SEC 1
J 0
(75 2450);
DISPLAY 0.680851 (75 2450);
PAINT MONO (75 2450);
DISPLAY INVISIBLE (75 2450);
FORCEPROP 2 LAST CDS_LOCATION R2L4
J 2
(80 2350);
DISPLAY 0.617021 (80 2350);
PAINT AQUA (80 2350);
DISPLAY INVISIBLE (80 2350);
FORCEPROP 1 LAST PATH I18
J 2
(75 2400);
DISPLAY 0.978723 (75 2400);
PAINT WHITE (75 2400);
DISPLAY INVISIBLE (75 2400);
FORCEPROP 0 LAST ROOM ST_SATA
J 0
(100 2450);
DISPLAY 1.021277 (100 2450);
PAINT ORANGE (100 2450);
DISPLAY INVISIBLE (100 2450);
FORCEADD P3V3_STBY..1
(-200 2625);
FORCEPROP 3 LASTPIN (-200 2575) SIG_NAME P3V3_STBY\g
J 0
(-190 2585);
DISPLAY 0.659574 (-190 2585);
PAINT MONO (-190 2585);
DISPLAY INVISIBLE (-190 2585);
FORCEPROP 1 LAST VOLTAGE 3.3V
J 0
(-245 2582);
DISPLAY 0.340426 (-245 2582);
PAINT SKYBLUE (-245 2582);
DISPLAY INVISIBLE (-245 2582);
FORCEPROP 2 LAST CDS_LIB mstr_symbols
J 0
(-200 2625);
PAINT MONO (-200 2625);
DISPLAY INVISIBLE (-200 2625);
FORCEPROP 1 LAST SIZE 1B
J 0
(-155 2647);
DISPLAY 0.340426 (-155 2647);
PAINT GREEN (-155 2647);
DISPLAY INVISIBLE (-155 2647);
FORCEPROP 1 LAST BODY_TYPE PLUMBING
J 0
(-245 2582);
DISPLAY 0.340426 (-245 2582);
PAINT GREEN (-245 2582);
DISPLAY INVISIBLE (-245 2582);
FORCEPROP 1 LAST PATH I19
J 0
(-155 2627);
DISPLAY 0.340426 (-155 2627);
PAINT GREEN (-155 2627);
DISPLAY INVISIBLE (-155 2627);
FORCEPROP 1 LAST HDL_POWER P3V3_STBY
J 0
(-500 2500);
DISPLAY 0.872340 (-500 2500);
PAINT ORANGE (-500 2500);
DISPLAY INVISIBLE (-500 2500);
FORCEADD RES..2
R 2
(-200 4125);
FORCEPROP 1 LAST LOCATION R2L12
J 2
(-245 4250);
DISPLAY 0.617021 (-245 4250);
PAINT AQUA (-245 4250);
FORCEPROP 1 LAST PART_NUMBER G21796-001
J 2
(-240 4000);
DISPLAY 0.617021 (-240 4000);
PAINT BLUE (-240 4000);
FORCEPROP 1 LAST VALUE 2.0K
J 2
(-245 4200);
DISPLAY 0.617021 (-245 4200);
PAINT SKYBLUE (-245 4200);
FORCEPROP 1 LAST TOLERANCE 1%
J 2
(-245 4150);
DISPLAY 0.617021 (-245 4150);
PAINT SKYBLUE (-245 4150);
FORCEPROP 1 LAST PACK_TYPE 0402
J 2
(-240 3950);
DISPLAY 0.617021 (-240 3950);
PAINT SKYBLUE (-240 3950);
FORCEPROP 1 LAST MATERIAL CHIP
J 2
(-240 4050);
DISPLAY 0.617021 (-240 4050);
PAINT SKYBLUE (-240 4050);
FORCEPROP 1 LAST WATTAGE 1/16W
J 2
(-240 4100);
DISPLAY 0.617021 (-240 4100);
PAINT SKYBLUE (-240 4100);
FORCEPROP 1 LASTPIN (-200 4025) $PN 2
J 2
(-205 4035);
DISPLAY 0.617021 (-205 4035);
PAINT ORANGE (-205 4035);
FORCEPROP 1 LASTPIN (-200 4225) $PN 1
J 2
(-205 4187);
DISPLAY 0.617021 (-205 4187);
PAINT ORANGE (-205 4187);
FORCEPROP 0 LAST BOM_COST ST_SATA
J 0
(-225 4350);
DISPLAY 1.021277 (-225 4350);
PAINT ORANGE (-225 4350);
DISPLAY INVISIBLE (-225 4350);
FORCEPROP 2 LAST SEC_TYPE 0402
J 0
(-250 4350);
DISPLAY 1.021277 (-250 4350);
PAINT ORANGE (-250 4350);
DISPLAY INVISIBLE (-250 4350);
FORCEPROP 2 LAST CDS_LIB mstr_discrete
J 0
(-200 4125);
PAINT MONO (-200 4125);
DISPLAY INVISIBLE (-200 4125);
FORCEPROP 2 LAST SEC 1
J 0
(-250 4350);
DISPLAY 0.680851 (-250 4350);
PAINT MONO (-250 4350);
DISPLAY INVISIBLE (-250 4350);
FORCEPROP 2 LAST CDS_LOCATION R2L12
J 2
(-245 4250);
DISPLAY 0.617021 (-245 4250);
PAINT AQUA (-245 4250);
DISPLAY INVISIBLE (-245 4250);
FORCEPROP 1 LAST PATH I2
J 2
(-250 4300);
DISPLAY 0.978723 (-250 4300);
PAINT WHITE (-250 4300);
DISPLAY INVISIBLE (-250 4300);
FORCEPROP 0 LAST ROOM ST_SATA
J 0
(-225 4350);
DISPLAY 1.021277 (-225 4350);
PAINT ORANGE (-225 4350);
DISPLAY INVISIBLE (-225 4350);
FORCEADD RES..2
R 2
(-200 2225);
FORCEPROP 1 LAST TOLERANCE 1%
J 2
(-245 2250);
DISPLAY 0.617021 (-245 2250);
PAINT SKYBLUE (-245 2250);
FORCEPROP 1 LAST PACK_TYPE 0402
J 2
(-240 2050);
DISPLAY 0.617021 (-240 2050);
PAINT SKYBLUE (-240 2050);
FORCEPROP 1 LAST MATERIAL CHIP
J 2
(-240 2150);
DISPLAY 0.617021 (-240 2150);
PAINT SKYBLUE (-240 2150);
FORCEPROP 1 LAST WATTAGE 1/16W
J 2
(-240 2200);
DISPLAY 0.617021 (-240 2200);
PAINT SKYBLUE (-240 2200);
FORCEPROP 1 LASTPIN (-200 2125) $PN 2
J 2
(-205 2135);
DISPLAY 0.617021 (-205 2135);
PAINT ORANGE (-205 2135);
FORCEPROP 1 LASTPIN (-200 2325) $PN 1
J 2
(-205 2287);
DISPLAY 0.617021 (-205 2287);
PAINT ORANGE (-205 2287);
FORCEPROP 1 LAST PART_NUMBER G21796-001
J 2
(-240 2100);
DISPLAY 0.617021 (-240 2100);
PAINT BLUE (-240 2100);
FORCEPROP 1 LAST VALUE 2.0K
J 2
(-245 2300);
DISPLAY 0.617021 (-245 2300);
PAINT SKYBLUE (-245 2300);
FORCEPROP 1 LAST LOCATION R2L5
J 2
(-245 2350);
DISPLAY 0.617021 (-245 2350);
PAINT AQUA (-245 2350);
FORCEPROP 2 LAST CDS_LIB mstr_discrete
J 0
(-200 2225);
PAINT MONO (-200 2225);
DISPLAY INVISIBLE (-200 2225);
FORCEPROP 2 LAST SEC_TYPE 0402
J 0
(-250 2450);
DISPLAY 1.021277 (-250 2450);
PAINT ORANGE (-250 2450);
DISPLAY INVISIBLE (-250 2450);
FORCEPROP 0 LAST BOM_COST ST_SATA
J 0
(-225 2450);
DISPLAY 1.021277 (-225 2450);
PAINT ORANGE (-225 2450);
DISPLAY INVISIBLE (-225 2450);
FORCEPROP 2 LAST SEC 1
J 0
(-250 2450);
DISPLAY 0.680851 (-250 2450);
PAINT MONO (-250 2450);
DISPLAY INVISIBLE (-250 2450);
FORCEPROP 2 LAST CDS_LOCATION R2L5
J 2
(-245 2350);
DISPLAY 0.617021 (-245 2350);
PAINT AQUA (-245 2350);
DISPLAY INVISIBLE (-245 2350);
FORCEPROP 1 LAST PATH I20
J 2
(-250 2400);
DISPLAY 0.978723 (-250 2400);
PAINT WHITE (-250 2400);
DISPLAY INVISIBLE (-250 2400);
FORCEPROP 0 LAST ROOM ST_SATA
J 0
(-225 2450);
DISPLAY 1.021277 (-225 2450);
PAINT ORANGE (-225 2450);
DISPLAY INVISIBLE (-225 2450);
FORCEADD RES..1
(-800 1675);
FORCEPROP 1 LAST LOCATION R8B29
J 0
(-825 1725);
DISPLAY 0.617021 (-825 1725);
PAINT AQUA (-825 1725);
FORCEPROP 1 LAST VALUE 49.9
J 2
(-825 1625);
DISPLAY 0.617021 (-825 1625);
PAINT SKYBLUE (-825 1625);
FORCEPROP 1 LAST TOLERANCE 1%
J 0
(-800 1625);
DISPLAY 0.617021 (-800 1625);
PAINT SKYBLUE (-800 1625);
FORCEPROP 1 LAST MATERIAL CHIP
J 0
(-725 1625);
DISPLAY 0.617021 (-725 1625);
PAINT SKYBLUE (-725 1625);
FORCEPROP 1 LAST WATTAGE 1/16W
J 2
(-925 1625);
DISPLAY 0.617021 (-925 1625);
PAINT SKYBLUE (-925 1625);
FORCEPROP 1 LASTPIN (-700 1675) $PN 2
J 0
(-738 1687);
DISPLAY 0.617021 (-738 1687);
PAINT ORANGE (-738 1687);
FORCEPROP 1 LASTPIN (-900 1675) $PN 1
J 0
(-888 1687);
DISPLAY 0.617021 (-888 1687);
PAINT ORANGE (-888 1687);
FORCEPROP 1 LAST PART_NUMBER G21796-047
J 0
(-525 1625);
DISPLAY 0.617021 (-525 1625);
PAINT BLUE (-525 1625);
FORCEPROP 1 LAST PACK_TYPE 0402
J 0
(-625 1625);
DISPLAY 0.617021 (-625 1625);
PAINT SKYBLUE (-625 1625);
FORCEPROP 0 LAST BOM_COST ST_SATA
J 0
(-800 1875);
DISPLAY 1.021277 (-800 1875);
PAINT ORANGE (-800 1875);
DISPLAY INVISIBLE (-800 1875);
FORCEPROP 2 LAST SEC_TYPE 0402
J 0
(-850 1875);
DISPLAY 1.021277 (-850 1875);
PAINT ORANGE (-850 1875);
DISPLAY INVISIBLE (-850 1875);
FORCEPROP 2 LAST CDS_LIB mstr_discrete
J 0
(-800 1675);
PAINT MONO (-800 1675);
DISPLAY INVISIBLE (-800 1675);
FORCEPROP 2 LAST SEC 1
J 0
(-850 1875);
DISPLAY 0.680851 (-850 1875);
PAINT MONO (-850 1875);
DISPLAY INVISIBLE (-850 1875);
FORCEPROP 2 LAST CDS_LOCATION R8B29
J 0
(-825 1725);
DISPLAY 0.617021 (-825 1725);
PAINT AQUA (-825 1725);
DISPLAY INVISIBLE (-825 1725);
FORCEPROP 1 LAST PATH I21
J 0
(-850 1825);
DISPLAY 0.978723 (-850 1825);
PAINT WHITE (-850 1825);
DISPLAY INVISIBLE (-850 1825);
FORCEPROP 0 LAST ROOM ST_SATA
J 0
(-850 1875);
DISPLAY 1.021277 (-850 1875);
PAINT ORANGE (-850 1875);
DISPLAY INVISIBLE (-850 1875);
FORCEADD RES..1
(-800 1825);
FORCEPROP 1 LAST LOCATION R2N19
J 0
(-825 1875);
DISPLAY 0.617021 (-825 1875);
PAINT AQUA (-825 1875);
FORCEPROP 1 LAST VALUE 49.9
J 2
(-825 1775);
DISPLAY 0.617021 (-825 1775);
PAINT SKYBLUE (-825 1775);
FORCEPROP 1 LAST TOLERANCE 1%
J 0
(-800 1775);
DISPLAY 0.617021 (-800 1775);
PAINT SKYBLUE (-800 1775);
FORCEPROP 1 LAST MATERIAL CHIP
J 0
(-725 1775);
DISPLAY 0.617021 (-725 1775);
PAINT SKYBLUE (-725 1775);
FORCEPROP 1 LAST WATTAGE 1/16W
J 2
(-925 1775);
DISPLAY 0.617021 (-925 1775);
PAINT SKYBLUE (-925 1775);
FORCEPROP 1 LASTPIN (-700 1825) $PN 2
J 0
(-738 1837);
DISPLAY 0.617021 (-738 1837);
PAINT ORANGE (-738 1837);
FORCEPROP 1 LASTPIN (-900 1825) $PN 1
J 0
(-888 1837);
DISPLAY 0.617021 (-888 1837);
PAINT ORANGE (-888 1837);
FORCEPROP 1 LAST PART_NUMBER G21796-047
J 0
(-525 1775);
DISPLAY 0.617021 (-525 1775);
PAINT BLUE (-525 1775);
FORCEPROP 1 LAST PACK_TYPE 0402
J 0
(-625 1775);
DISPLAY 0.617021 (-625 1775);
PAINT SKYBLUE (-625 1775);
FORCEPROP 0 LAST BOM_COST ST_SATA
J 0
(-800 2025);
DISPLAY 1.021277 (-800 2025);
PAINT ORANGE (-800 2025);
DISPLAY INVISIBLE (-800 2025);
FORCEPROP 2 LAST SEC_TYPE 0402
J 0
(-850 2025);
DISPLAY 1.021277 (-850 2025);
PAINT ORANGE (-850 2025);
DISPLAY INVISIBLE (-850 2025);
FORCEPROP 2 LAST CDS_LIB mstr_discrete
J 0
(-800 1825);
PAINT MONO (-800 1825);
DISPLAY INVISIBLE (-800 1825);
FORCEPROP 2 LAST SEC 1
J 0
(-850 2025);
DISPLAY 0.680851 (-850 2025);
PAINT MONO (-850 2025);
DISPLAY INVISIBLE (-850 2025);
FORCEPROP 2 LAST CDS_LOCATION R2N19
J 0
(-825 1875);
DISPLAY 0.617021 (-825 1875);
PAINT AQUA (-825 1875);
DISPLAY INVISIBLE (-825 1875);
FORCEPROP 1 LAST PATH I22
J 0
(-850 1975);
DISPLAY 0.978723 (-850 1975);
PAINT WHITE (-850 1975);
DISPLAY INVISIBLE (-850 1975);
FORCEPROP 0 LAST ROOM ST_SATA
J 0
(-850 2025);
DISPLAY 1.021277 (-850 2025);
PAINT ORANGE (-850 2025);
DISPLAY INVISIBLE (-850 2025);
FORCEADD RES..1
(-800 1525);
FORCEPROP 1 LAST LOCATION R2N22
J 0
(-825 1575);
DISPLAY 0.617021 (-825 1575);
PAINT AQUA (-825 1575);
FORCEPROP 1 LAST PART_NUMBER G21796-047
J 0
(-525 1475);
DISPLAY 0.617021 (-525 1475);
PAINT BLUE (-525 1475);
FORCEPROP 1 LAST VALUE 49.9
J 2
(-825 1475);
DISPLAY 0.617021 (-825 1475);
PAINT SKYBLUE (-825 1475);
FORCEPROP 1 LAST TOLERANCE 1%
J 0
(-800 1475);
DISPLAY 0.617021 (-800 1475);
PAINT SKYBLUE (-800 1475);
FORCEPROP 1 LAST PACK_TYPE 0402
J 0
(-625 1475);
DISPLAY 0.617021 (-625 1475);
PAINT SKYBLUE (-625 1475);
FORCEPROP 1 LAST MATERIAL CHIP
J 0
(-725 1475);
DISPLAY 0.617021 (-725 1475);
PAINT SKYBLUE (-725 1475);
FORCEPROP 1 LAST WATTAGE 1/16W
J 2
(-925 1475);
DISPLAY 0.617021 (-925 1475);
PAINT SKYBLUE (-925 1475);
FORCEPROP 1 LASTPIN (-700 1525) $PN 2
J 0
(-738 1537);
DISPLAY 0.617021 (-738 1537);
PAINT ORANGE (-738 1537);
FORCEPROP 1 LASTPIN (-900 1525) $PN 1
J 0
(-888 1537);
DISPLAY 0.617021 (-888 1537);
PAINT ORANGE (-888 1537);
FORCEPROP 0 LAST BOM_COST ST_SATA
J 0
(-800 1725);
DISPLAY 1.021277 (-800 1725);
PAINT ORANGE (-800 1725);
DISPLAY INVISIBLE (-800 1725);
FORCEPROP 2 LAST SEC_TYPE 0402
J 0
(-850 1725);
DISPLAY 1.021277 (-850 1725);
PAINT ORANGE (-850 1725);
DISPLAY INVISIBLE (-850 1725);
FORCEPROP 2 LAST CDS_LIB mstr_discrete
J 0
(-800 1525);
PAINT MONO (-800 1525);
DISPLAY INVISIBLE (-800 1525);
FORCEPROP 2 LAST SEC 1
J 0
(-850 1725);
DISPLAY 0.680851 (-850 1725);
PAINT MONO (-850 1725);
DISPLAY INVISIBLE (-850 1725);
FORCEPROP 2 LAST CDS_LOCATION R2N22
J 0
(-825 1575);
DISPLAY 0.617021 (-825 1575);
PAINT AQUA (-825 1575);
DISPLAY INVISIBLE (-825 1575);
FORCEPROP 1 LAST PATH I23
J 0
(-850 1675);
DISPLAY 0.978723 (-850 1675);
PAINT WHITE (-850 1675);
DISPLAY INVISIBLE (-850 1675);
FORCEPROP 0 LAST ROOM ST_SATA
J 0
(-850 1725);
DISPLAY 1.021277 (-850 1725);
PAINT ORANGE (-850 1725);
DISPLAY INVISIBLE (-850 1725);
FORCEADD OFFPAGE..1
(-1700 1675);
FORCEPROP 2 LAST $XR0 119 
J 0
(-1952 1675);
DISPLAY 0.638298 (-1952 1675);
PAINT MONO (-1952 1675);
FORCEPROP 2 LAST CDS_LIB mstr_standard
J 0
(-1700 1675);
PAINT MONO (-1700 1675);
DISPLAY INVISIBLE (-1700 1675);
FORCEPROP 1 LAST OFFPAGE TRUE
J 0
(-1375 1550);
DISPLAY 0.872340 (-1375 1550);
PAINT GREEN (-1375 1550);
DISPLAY INVISIBLE (-1375 1550);
FORCEPROP 1 LAST COMMENT_BODY TRUE
J 0
(-1575 1575);
DISPLAY 0.872340 (-1575 1575);
PAINT GREEN (-1575 1575);
DISPLAY INVISIBLE (-1575 1575);
FORCEPROP 2 LAST PATH I24
J 0
(-1650 1750);
DISPLAY 1.021277 (-1650 1750);
PAINT ORANGE (-1650 1750);
DISPLAY INVISIBLE (-1650 1750);
FORCEADD OFFPAGE..1
(-1700 1825);
FORCEPROP 2 LAST $XR0 120 
J 0
(-1952 1825);
DISPLAY 0.638298 (-1952 1825);
PAINT MONO (-1952 1825);
FORCEPROP 2 LAST CDS_LIB mstr_standard
J 0
(-1700 1825);
PAINT MONO (-1700 1825);
DISPLAY INVISIBLE (-1700 1825);
FORCEPROP 1 LAST OFFPAGE TRUE
J 0
(-1375 1700);
DISPLAY 0.872340 (-1375 1700);
PAINT GREEN (-1375 1700);
DISPLAY INVISIBLE (-1375 1700);
FORCEPROP 1 LAST COMMENT_BODY TRUE
J 0
(-1575 1725);
DISPLAY 0.872340 (-1575 1725);
PAINT GREEN (-1575 1725);
DISPLAY INVISIBLE (-1575 1725);
FORCEPROP 2 LAST PATH I25
J 0
(-1650 1900);
DISPLAY 1.021277 (-1650 1900);
PAINT ORANGE (-1650 1900);
DISPLAY INVISIBLE (-1650 1900);
FORCEADD OFFPAGE..1
(-1700 1525);
FORCEPROP 2 LAST $XR0 120 
J 0
(-1952 1525);
DISPLAY 0.638298 (-1952 1525);
PAINT MONO (-1952 1525);
FORCEPROP 2 LAST CDS_LIB mstr_standard
J 0
(-1700 1525);
PAINT MONO (-1700 1525);
DISPLAY INVISIBLE (-1700 1525);
FORCEPROP 1 LAST OFFPAGE TRUE
J 0
(-1375 1400);
DISPLAY 0.872340 (-1375 1400);
PAINT GREEN (-1375 1400);
DISPLAY INVISIBLE (-1375 1400);
FORCEPROP 1 LAST COMMENT_BODY TRUE
J 0
(-1575 1425);
DISPLAY 0.872340 (-1575 1425);
PAINT GREEN (-1575 1425);
DISPLAY INVISIBLE (-1575 1425);
FORCEPROP 2 LAST PATH I26
J 0
(-1650 1600);
DISPLAY 1.021277 (-1650 1600);
PAINT ORANGE (-1650 1600);
DISPLAY INVISIBLE (-1650 1600);
FORCEADD OFFPAGE..1
(-1700 3725);
FORCEPROP 2 LAST $XR0 120 
J 0
(-1952 3725);
DISPLAY 0.638298 (-1952 3725);
PAINT MONO (-1952 3725);
FORCEPROP 2 LAST CDS_LIB mstr_standard
J 0
(-1700 3725);
PAINT MONO (-1700 3725);
DISPLAY INVISIBLE (-1700 3725);
FORCEPROP 1 LAST OFFPAGE TRUE
J 0
(-1375 3600);
DISPLAY 0.872340 (-1375 3600);
PAINT GREEN (-1375 3600);
DISPLAY INVISIBLE (-1375 3600);
FORCEPROP 1 LAST COMMENT_BODY TRUE
J 0
(-1575 3625);
DISPLAY 0.872340 (-1575 3625);
PAINT GREEN (-1575 3625);
DISPLAY INVISIBLE (-1575 3625);
FORCEPROP 2 LAST PATH I3
J 0
(-1650 3800);
DISPLAY 1.021277 (-1650 3800);
PAINT ORANGE (-1650 3800);
DISPLAY INVISIBLE (-1650 3800);
FORCEADD OFFPAGE..2
(1450 3725);
FORCEPROP 2 LAST $XR0 173 
J 0
(1639 3725);
DISPLAY 0.638298 (1639 3725);
PAINT MONO (1639 3725);
FORCEPROP 2 LAST CDS_LIB mstr_standard
J 0
(1450 3725);
PAINT MONO (1450 3725);
DISPLAY INVISIBLE (1450 3725);
FORCEPROP 1 LAST OFFPAGE TRUE
J 0
(1775 3600);
DISPLAY 0.872340 (1775 3600);
PAINT GREEN (1775 3600);
DISPLAY INVISIBLE (1775 3600);
FORCEPROP 1 LAST COMMENT_BODY TRUE
J 0
(1405 3630);
DISPLAY 0.872340 (1405 3630);
PAINT GREEN (1405 3630);
DISPLAY INVISIBLE (1405 3630);
FORCEPROP 2 LAST PATH I4
J 0
(1625 3800);
DISPLAY 1.021277 (1625 3800);
PAINT ORANGE (1625 3800);
DISPLAY INVISIBLE (1625 3800);
FORCEADD P3V3_STBY..1
(-200 4525);
FORCEPROP 3 LASTPIN (-200 4475) SIG_NAME P3V3_STBY\g
J 0
(-190 4485);
DISPLAY 0.659574 (-190 4485);
PAINT MONO (-190 4485);
DISPLAY INVISIBLE (-190 4485);
FORCEPROP 1 LAST VOLTAGE 3.3V
J 0
(-245 4482);
DISPLAY 0.340426 (-245 4482);
PAINT SKYBLUE (-245 4482);
DISPLAY INVISIBLE (-245 4482);
FORCEPROP 1 LAST SIZE 1B
J 0
(-155 4547);
DISPLAY 0.340426 (-155 4547);
PAINT GREEN (-155 4547);
DISPLAY INVISIBLE (-155 4547);
FORCEPROP 2 LAST CDS_LIB mstr_symbols
J 0
(-200 4525);
PAINT MONO (-200 4525);
DISPLAY INVISIBLE (-200 4525);
FORCEPROP 1 LAST BODY_TYPE PLUMBING
J 0
(-245 4482);
DISPLAY 0.340426 (-245 4482);
PAINT GREEN (-245 4482);
DISPLAY INVISIBLE (-245 4482);
FORCEPROP 1 LAST PATH I5
J 0
(-155 4527);
DISPLAY 0.340426 (-155 4527);
PAINT GREEN (-155 4527);
DISPLAY INVISIBLE (-155 4527);
FORCEPROP 1 LAST HDL_POWER P3V3_STBY
J 0
(-500 4400);
DISPLAY 0.872340 (-500 4400);
PAINT ORANGE (-500 4400);
DISPLAY INVISIBLE (-500 4400);
FORCEADD OFFPAGE..1
(-1700 3575);
FORCEPROP 2 LAST $XR0 120 
J 0
(-1952 3575);
DISPLAY 0.638298 (-1952 3575);
PAINT MONO (-1952 3575);
FORCEPROP 2 LAST CDS_LIB mstr_standard
J 0
(-1700 3575);
PAINT MONO (-1700 3575);
DISPLAY INVISIBLE (-1700 3575);
FORCEPROP 1 LAST OFFPAGE TRUE
J 0
(-1375 3450);
DISPLAY 0.872340 (-1375 3450);
PAINT GREEN (-1375 3450);
DISPLAY INVISIBLE (-1375 3450);
FORCEPROP 1 LAST COMMENT_BODY TRUE
J 0
(-1575 3475);
DISPLAY 0.872340 (-1575 3475);
PAINT GREEN (-1575 3475);
DISPLAY INVISIBLE (-1575 3475);
FORCEPROP 2 LAST PATH I6
J 0
(-1650 3650);
DISPLAY 1.021277 (-1650 3650);
PAINT ORANGE (-1650 3650);
DISPLAY INVISIBLE (-1650 3650);
FORCEADD OFFPAGE..2
(1450 3575);
FORCEPROP 2 LAST $XR0 173 
J 0
(1639 3575);
DISPLAY 0.638298 (1639 3575);
PAINT MONO (1639 3575);
FORCEPROP 2 LAST CDS_LIB mstr_standard
J 0
(1450 3575);
PAINT MONO (1450 3575);
DISPLAY INVISIBLE (1450 3575);
FORCEPROP 1 LAST OFFPAGE TRUE
J 0
(1775 3450);
DISPLAY 0.872340 (1775 3450);
PAINT GREEN (1775 3450);
DISPLAY INVISIBLE (1775 3450);
FORCEPROP 1 LAST COMMENT_BODY TRUE
J 0
(1405 3480);
DISPLAY 0.872340 (1405 3480);
PAINT GREEN (1405 3480);
DISPLAY INVISIBLE (1405 3480);
FORCEPROP 2 LAST PATH I7
J 0
(1625 3650);
DISPLAY 1.021277 (1625 3650);
PAINT ORANGE (1625 3650);
DISPLAY INVISIBLE (1625 3650);
FORCEADD RES..1
(-800 3575);
FORCEPROP 1 LAST LOCATION R8D19
J 0
(-825 3625);
DISPLAY 0.617021 (-825 3625);
PAINT AQUA (-825 3625);
FORCEPROP 1 LAST PART_NUMBER G21796-047
J 0
(-525 3525);
DISPLAY 0.617021 (-525 3525);
PAINT BLUE (-525 3525);
FORCEPROP 1 LAST VALUE 49.9
J 2
(-825 3525);
DISPLAY 0.617021 (-825 3525);
PAINT SKYBLUE (-825 3525);
FORCEPROP 1 LAST TOLERANCE 1%
J 0
(-800 3525);
DISPLAY 0.617021 (-800 3525);
PAINT SKYBLUE (-800 3525);
FORCEPROP 1 LAST PACK_TYPE 0402
J 0
(-625 3525);
DISPLAY 0.617021 (-625 3525);
PAINT SKYBLUE (-625 3525);
FORCEPROP 1 LAST MATERIAL CHIP
J 0
(-725 3525);
DISPLAY 0.617021 (-725 3525);
PAINT SKYBLUE (-725 3525);
FORCEPROP 1 LAST WATTAGE 1/16W
J 2
(-925 3525);
DISPLAY 0.617021 (-925 3525);
PAINT SKYBLUE (-925 3525);
FORCEPROP 1 LASTPIN (-700 3575) $PN 2
J 0
(-738 3587);
DISPLAY 0.617021 (-738 3587);
PAINT ORANGE (-738 3587);
FORCEPROP 1 LASTPIN (-900 3575) $PN 1
J 0
(-888 3587);
DISPLAY 0.617021 (-888 3587);
PAINT ORANGE (-888 3587);
FORCEPROP 2 LAST CDS_LIB mstr_discrete
J 0
(-800 3575);
PAINT MONO (-800 3575);
DISPLAY INVISIBLE (-800 3575);
FORCEPROP 2 LAST SEC_TYPE 0402
J 0
(-850 3775);
DISPLAY 1.021277 (-850 3775);
PAINT ORANGE (-850 3775);
DISPLAY INVISIBLE (-850 3775);
FORCEPROP 0 LAST BOM_COST ST_SATA
J 0
(-800 3775);
DISPLAY 1.021277 (-800 3775);
PAINT ORANGE (-800 3775);
DISPLAY INVISIBLE (-800 3775);
FORCEPROP 2 LAST SEC 1
J 0
(-850 3775);
DISPLAY 0.680851 (-850 3775);
PAINT MONO (-850 3775);
DISPLAY INVISIBLE (-850 3775);
FORCEPROP 2 LAST CDS_LOCATION R8D19
J 0
(-825 3625);
DISPLAY 0.617021 (-825 3625);
PAINT AQUA (-825 3625);
DISPLAY INVISIBLE (-825 3625);
FORCEPROP 1 LAST PATH I8
J 0
(-850 3725);
DISPLAY 0.978723 (-850 3725);
PAINT WHITE (-850 3725);
DISPLAY INVISIBLE (-850 3725);
FORCEPROP 0 LAST ROOM ST_SATA
J 0
(-850 3775);
DISPLAY 1.021277 (-850 3775);
PAINT ORANGE (-850 3775);
DISPLAY INVISIBLE (-850 3775);
FORCEADD OFFPAGE..1
(-1700 3425);
FORCEPROP 2 LAST $XR0 120 
J 0
(-1952 3425);
DISPLAY 0.638298 (-1952 3425);
PAINT MONO (-1952 3425);
FORCEPROP 2 LAST CDS_LIB mstr_standard
J 0
(-1700 3425);
PAINT MONO (-1700 3425);
DISPLAY INVISIBLE (-1700 3425);
FORCEPROP 1 LAST OFFPAGE TRUE
J 0
(-1375 3300);
DISPLAY 0.872340 (-1375 3300);
PAINT GREEN (-1375 3300);
DISPLAY INVISIBLE (-1375 3300);
FORCEPROP 1 LAST COMMENT_BODY TRUE
J 0
(-1575 3325);
DISPLAY 0.872340 (-1575 3325);
PAINT GREEN (-1575 3325);
DISPLAY INVISIBLE (-1575 3325);
FORCEPROP 2 LAST PATH I9
J 0
(-1650 3500);
DISPLAY 1.021277 (-1650 3500);
PAINT ORANGE (-1650 3500);
DISPLAY INVISIBLE (-1650 3500);
FORCEADD DESIGN_NOTE..1
(-875 1275);
FORCEPROP 0 LAST L1 PLACE RESISTORS <2 INCHES FROM PCH
J 0
(-1075 1125);
DISPLAY 1.021277 (-1075 1125);
PAINT ORANGE (-1075 1125);
FORCEPROP 2 LAST CDS_LIB mstr_symbols
J 0
(-875 1275);
PAINT MONO (-875 1275);
DISPLAY INVISIBLE (-875 1275);
FORCEPROP 1 LAST COMMENT_BODY TRUE
J 0
(-850 1375);
DISPLAY 0.978723 (-850 1375);
PAINT ORANGE (-850 1375);
DISPLAY INVISIBLE (-850 1375);
FORCEADD INTEL_CORP_BPAGE..1
(4250 200);
FORCEPROP 1 LAST CDS_CON_LAST_MODIFIED Fri Jun 16 17:49:06 2017
J 0
(2825 525);
PAINT ORANGE (2825 525);
DISPLAY INVISIBLE (2825 525);
FORCEPROP 1 LAST CUSTOM_TXT_CDS <CURRENT_DESIGN_SHEET> OF <TOTAL_DESIGN_SHEETS>
J 0
(3750 225);
PAINT ORANGE (3750 225);
FORCEPROP 1 LAST CUSTOM_TXT_CDS <CON_LAST_MODIFIED>
J 0
(250 300);
PAINT ORANGE (250 300);
FORCEPROP 2 LAST CUSTOM_TXT_CDS <XR_PAGE_TITLE>
J 0
(-3640 5450);
DISPLAY 0.638298 (-3640 5450);
PAINT PINK (-3640 5450);
DISPLAY INVISIBLE (-3640 5450);
FORCEPROP 1 LAST SCH_TITLE SATA SGPIO CONNECTORS
J 0
(-3700 250);
DISPLAY 1.212766 (-3700 250);
PAINT YELLOW (-3700 250);
FORCEPROP 2 LAST CDS_LIB mstr_symbols
J 0
(4250 200);
PAINT MONO (4250 200);
DISPLAY INVISIBLE (4250 200);
FORCEPROP 2 LAST PAGE_BORDER TRUE
J 0
(-3640 5450);
DISPLAY 0.638298 (-3640 5450);
PAINT PINK (-3640 5450);
DISPLAY INVISIBLE (-3640 5450);
FORCEPROP 1 LAST COMMENT_BODY TRUE
J 0
(4262 212);
DISPLAY 0.468085 (4262 212);
PAINT PEACH (4262 212);
DISPLAY INVISIBLE (4262 212);
FORCEPROP 2 LAST CDS_XR_PAGE_TITLE CR-178 : @BASEBOARD_FAB2_LIB.BASEBOARD_FAB2(SCH_1):PAGE178
J 0
(-3640 5450);
DISPLAY 0.638298 (-3640 5450);
PAINT PINK (-3640 5450);
DISPLAY INVISIBLE (-3640 5450);
FORCEADD DESIGN_NOTE..1
(-875 3175);
FORCEPROP 0 LAST L1 PLACE RESISTORS <2 INCHES FROM PCH
J 0
(-1075 3025);
DISPLAY 1.021277 (-1075 3025);
PAINT ORANGE (-1075 3025);
FORCEPROP 2 LAST CDS_LIB mstr_symbols
J 0
(-875 3175);
PAINT MONO (-875 3175);
DISPLAY INVISIBLE (-875 3175);
FORCEPROP 1 LAST COMMENT_BODY TRUE
J 0
(-850 3275);
DISPLAY 0.978723 (-850 3275);
PAINT ORANGE (-850 3275);
DISPLAY INVISIBLE (-850 3275);
FORCEADD DESIGN_NOTE..1
(975 4350);
FORCEPROP 0 LAST L1 PLACE RESISTORS CLOSE TO MINI SAS CONNECTOR
J 0
(775 4225);
DISPLAY 1.021277 (775 4225);
PAINT ORANGE (775 4225);
FORCEPROP 2 LAST CDS_LIB mstr_symbols
J 0
(975 4350);
PAINT MONO (975 4350);
DISPLAY INVISIBLE (975 4350);
FORCEPROP 1 LAST COMMENT_BODY TRUE
J 0
(1000 4450);
DISPLAY 0.978723 (1000 4450);
PAINT ORANGE (1000 4450);
DISPLAY INVISIBLE (1000 4450);
FORCEADD DESIGN_NOTE..1
(950 2450);
FORCEPROP 0 LAST L1 PLACE RESISTORS CLOSE TO MINI SAS CONNECTOR
J 0
(750 2325);
DISPLAY 1.021277 (750 2325);
PAINT ORANGE (750 2325);
FORCEPROP 2 LAST CDS_LIB mstr_symbols
J 0
(950 2450);
PAINT MONO (950 2450);
DISPLAY INVISIBLE (950 2450);
FORCEPROP 1 LAST COMMENT_BODY TRUE
J 0
(975 2550);
DISPLAY 0.978723 (975 2550);
PAINT ORANGE (975 2550);
DISPLAY INVISIBLE (975 2550);
WIRE 16 -1 (-200 2450)(-200 2575);
WIRE 16 -1 (125 2450)(-200 2450);
WIRE 16 -1 (-200 2325)(-200 2450);
WIRE 16 -1 (475 2450)(125 2450);
WIRE 16 -1 (125 2325)(125 2450);
WIRE 16 -1 (475 2325)(475 2450);
WIRE 16 -1 (-200 4350)(-200 4475);
WIRE 16 -1 (225 4350)(-200 4350);
WIRE 16 -1 (-200 4225)(-200 4350);
WIRE 16 -1 (575 4350)(225 4350);
WIRE 16 -1 (225 4225)(225 4350);
WIRE 16 -1 (575 4225)(575 4350);
WIRE 16 273 (-475 3875)(-475 4400);
WIRE 16 273 (675 3875)(-475 3875);
WIRE 16 273 (675 4400)(-475 4400);
WIRE 16 273 (675 4400)(675 3875);
WIRE 16 -1 (225 3575)(-700 3575);
WIRE 16 -1 (1400 3575)(225 3575);
FORCEPROP 2 LAST SIG_NAME SGPIO_PCH_SATA_DOUT0_R
J 0
(740 3585);
DISPLAY 0.617021 (740 3585);
PAINT ORANGE (740 3585);
WIRE 16 -1 (225 4025)(225 3575);
WIRE 16 -1 (-700 1525)(475 1525);
WIRE 16 -1 (475 2125)(475 1525);
WIRE 16 -1 (1400 1525)(475 1525);
FORCEPROP 2 LAST SIG_NAME SGPIO_PCH_SSATA_CLOCK_R
J 0
(715 1535);
DISPLAY 0.617021 (715 1535);
PAINT ORANGE (715 1535);
FORCEPROP 2 LASTPROP $XRERR UNIQUE?
J 0
(1430 1525);
DISPLAY 0.638298 (1430 1525);
PAINT MONO (1430 1525);
DISPLAY INVISIBLE (1430 1525);
WIRE 16 -1 (125 1675)(-700 1675);
WIRE 16 -1 (125 2125)(125 1675);
WIRE 16 -1 (1400 1675)(125 1675);
FORCEPROP 2 LAST SIG_NAME SGPIO_PCH_SSATA_DOUT0_R
J 0
(715 1685);
DISPLAY 0.617021 (715 1685);
PAINT ORANGE (715 1685);
FORCEPROP 2 LASTPROP $XRERR UNIQUE?
J 0
(1430 1675);
DISPLAY 0.638298 (1430 1675);
PAINT MONO (1430 1675);
DISPLAY INVISIBLE (1430 1675);
WIRE 16 -1 (-700 1825)(-200 1825);
WIRE 16 -1 (-200 2125)(-200 1825);
WIRE 16 -1 (1400 1825)(-200 1825);
FORCEPROP 2 LAST SIG_NAME SGPIO_PCH_SSATA_LOAD_R
J 0
(715 1835);
DISPLAY 0.617021 (715 1835);
PAINT ORANGE (715 1835);
FORCEPROP 2 LASTPROP $XRERR UNIQUE?
J 0
(1430 1825);
DISPLAY 0.638298 (1430 1825);
PAINT MONO (1430 1825);
DISPLAY INVISIBLE (1430 1825);
WIRE 16 273 (-500 1975)(-500 2500);
WIRE 16 273 (650 1975)(-500 1975);
WIRE 16 273 (650 2500)(-500 2500);
WIRE 16 273 (650 2500)(650 1975);
WIRE 16 -1 (575 4025)(575 3425);
WIRE 16 -1 (1400 3425)(575 3425);
FORCEPROP 2 LAST SIG_NAME SGPIO_PCH_SATA_CLOCK_R
J 0
(740 3435);
DISPLAY 0.617021 (740 3435);
PAINT ORANGE (740 3435);
WIRE 16 -1 (-700 3425)(575 3425);
WIRE 16 -1 (-700 3725)(-200 3725);
WIRE 16 -1 (-200 4025)(-200 3725);
WIRE 16 -1 (1400 3725)(-200 3725);
FORCEPROP 2 LAST SIG_NAME SGPIO_PCH_SATA_LOAD_R
J 0
(740 3735);
DISPLAY 0.617021 (740 3735);
PAINT ORANGE (740 3735);
WIRE 16 273 (-1075 1375)(-1075 1975);
WIRE 16 273 (-525 1375)(-1075 1375);
WIRE 16 273 (-525 1975)(-1075 1975);
WIRE 16 273 (-525 1975)(-525 1375);
WIRE 16 273 (-1100 3275)(-1100 3875);
WIRE 16 273 (-550 3275)(-1100 3275);
WIRE 16 273 (-550 3875)(-1100 3875);
WIRE 16 273 (-550 3875)(-550 3275);
WIRE 16 -1 (-900 1675)(-1650 1675);
FORCEPROP 2 LAST SIG_NAME SGPIO_PCH_SSATA_DOUT0
J 0
(-1610 1685);
DISPLAY 0.617021 (-1610 1685);
PAINT ORANGE (-1610 1685);
WIRE 16 -1 (-900 1825)(-1650 1825);
FORCEPROP 2 LAST SIG_NAME SGPIO_PCH_SSATA_LOAD
J 0
(-1610 1835);
DISPLAY 0.617021 (-1610 1835);
PAINT ORANGE (-1610 1835);
WIRE 16 -1 (-900 1525)(-1650 1525);
FORCEPROP 2 LAST SIG_NAME SGPIO_PCH_SSATA_CLOCK
J 0
(-1610 1535);
DISPLAY 0.617021 (-1610 1535);
PAINT ORANGE (-1610 1535);
WIRE 16 -1 (-900 3725)(-1650 3725);
FORCEPROP 2 LAST SIG_NAME SGPIO_PCH_SATA_LOAD
J 0
(-1610 3735);
DISPLAY 0.617021 (-1610 3735);
PAINT ORANGE (-1610 3735);
WIRE 16 -1 (-900 3575)(-1650 3575);
FORCEPROP 2 LAST SIG_NAME SGPIO_PCH_SATA_DOUT0
J 0
(-1610 3585);
DISPLAY 0.617021 (-1610 3585);
PAINT ORANGE (-1610 3585);
WIRE 16 -1 (-900 3425)(-1650 3425);
FORCEPROP 2 LAST SIG_NAME SGPIO_PCH_SATA_CLOCK
J 0
(-1610 3435);
DISPLAY 0.617021 (-1610 3435);
PAINT ORANGE (-1610 3435);
DOT 1 (-200 1825);
DOT 1 (475 1525);
DOT 1 (125 1675);
DOT 1 (575 3425);
DOT 1 (225 4350);
DOT 1 (-200 4350);
DOT 1 (125 2450);
DOT 1 (-200 3725);
DOT 1 (-200 2450);
DOT 1 (225 3575);
FORCENOTE
X4 SSATA DOWN CONN
(-75 2775) 0;
DISPLAY LEFT (-75 2775);
DISPLAY 1.021277 (-75 2775);
PAINT PURPLE (-75 2775);
FORCENOTE
BOM_COST=ST_SATA
(-3600 450) 0;
DISPLAY LEFT (-3600 450);
DISPLAY 1.382979 (-3600 450);
PAINT PURPLE (-3600 450);
FORCENOTE
ROOM=ST_SATA
(-3600 575) 0;
DISPLAY LEFT (-3600 575);
DISPLAY 1.382979 (-3600 575);
PAINT PURPLE (-3600 575);
FORCENOTE
X8 MINI-SAS VERTICAL PCH PCIE_UP
(-125 4700) 0;
DISPLAY LEFT (-125 4700);
DISPLAY 1.021277 (-125 4700);
PAINT PURPLE (-125 4700);
QUIT
